# T6G (Grand Teton) — schematic netlist excerpt (pin names and nets, part order shuffled) for the footprints in the layout excerpt that follows; sources: Cadence DE-HDL packaged netlist, KiCad conversion of 04192023_DAF0TMB3IC0_F0TG_MB_C_brd_V02_OCP.brd

PR2519  Q_RES  100 1% CHIP  pkg 0402LF  page 266 : A = P12V_HSC_ADC_N ; B = P12V_HSC_SENSE1_N
R1068  Q_RES  0 5% CHIP  pkg 0201LF  page 298 : A = SMB_RT_CPU0_P2_R_SDA ; B = SMB_RT_CPU0_P2_R2_SDA
R96  Q_RES  1K 1% EMPTY  pkg 0402LF  page 92 : A = P3V3 ; B = PWRGD_CHG_CPU0_DIMM0

(kicad_pcb
	(version 20260206)
	(generator "pcbnew")
	(generator_version "10.0")
	(general
		(thickness 1.6)
		(legacy_teardrops no)
	)
	(paper "A4")
	(title_block
		(title "04192023_DAF0TMB3IC0_F0TG_MB_C_brd_V02_OCP.brd")
		(comment 1 "Grand Teton / footprints 8144-8146 of 8354")
	)
	(layers
		(0 "F.Cu" signal "TOP")
		(4 "In1.Cu" signal "GND")
		(6 "In2.Cu" signal "IN1")
		(8 "In3.Cu" signal "GND1")
		(10 "In4.Cu" signal "IN2")
		(12 "In5.Cu" signal "GND2")
		(14 "In6.Cu" signal "IN3")
		(16 "In7.Cu" signal "GND3")
		(18 "In8.Cu" signal "VCC")
		(20 "In9.Cu" signal "VCC1")
		(22 "In10.Cu" signal "GND4")
		(24 "In11.Cu" signal "IN4")
		(26 "In12.Cu" signal "GND5")
		(28 "In13.Cu" signal "IN5")
		(30 "In14.Cu" signal "GND6")
		(32 "In15.Cu" signal "IN6")
		(34 "In16.Cu" signal "GND7")
		(2 "B.Cu" signal "BOTTOM")
		(9 "F.Adhes" user "F.Adhesive")
		(11 "B.Adhes" user "B.Adhesive")
		(13 "F.Paste" user "Package Geometry/Pastemask Top")
		(15 "B.Paste" user "Package Geometry/Pastemask Bottom")
		(5 "F.SilkS" user "Ref Des/Silkscreen Top")
		(7 "B.SilkS" user "Ref Des/Silkscreen Bottom")
		(1 "F.Mask" user "Board Geometry/Soldermask Top")
		(3 "B.Mask" user "Board Geometry/Soldermask Bottom")
		(17 "Dwgs.User" user "User.Drawings")
		(19 "Cmts.User" user "User.Comments")
		(21 "Eco1.User" user "User.Eco1")
		(23 "Eco2.User" user "User.Eco2")
		(25 "Edge.Cuts" user "Board Geometry/Outline")
		(27 "Margin" user)
		(31 "F.CrtYd" user "Package Geometry/Place Bound Top")
		(29 "B.CrtYd" user "Package Geometry/Place Bound Bottom")
		(35 "F.Fab" user "Ref Des/Assembly Top")
		(33 "B.Fab" user "Ref Des/Assembly Bottom")
	)
	(footprint ""
		(layer "B.Cu")
		(at 233.807 -335.026 180)
		(property "Reference" "R1068"
			(at 0 0 0)
			(layer "B.SilkS")
			(hide yes)
			(effects
				(font
					(size 1.27 1.27)
				)
				(justify mirror)
			)
		)
		(property "Value" ""
			(at 0 0 0)
			(layer "B.Fab")
			(effects
				(font
					(size 1.27 1.27)
				)
				(justify mirror)
			)
		)
		(duplicate_pad_numbers_are_jumpers no)
		(fp_line
			(start 0.32512 0.175006)
			(end 0.32512 -0.175006)
			(stroke
				(width 0.1)
				(type default)
			)
			(layer "B.Fab")
		)
		(fp_line
			(start 0.32512 -0.175006)
			(end -0.32512 -0.175006)
			(stroke
				(width 0.1)
				(type default)
			)
			(layer "B.Fab")
		)
		(fp_line
			(start -0.32512 0.175006)
			(end 0.32512 0.175006)
			(stroke
				(width 0.1)
				(type default)
			)
			(layer "B.Fab")
		)
		(fp_line
			(start -0.32512 -0.175006)
			(end -0.32512 0.175006)
			(stroke
				(width 0.1)
				(type default)
			)
			(layer "B.Fab")
		)
		(pad "1" smd rect
			(at 0.2667 0)
			(size 0.3048 0.381)
			(layers "B.Cu" "B.Mask" "B.Paste")
			(net "SMB_RT_CPU0_P2_R_SDA")
		)
		(pad "2" smd rect
			(at -0.2667 0 180)
			(size 0.3048 0.381)
			(layers "B.Cu" "B.Mask" "B.Paste")
			(net "SMB_RT_CPU0_P2_R2_SDA")
		)
	)
	(footprint ""
		(layer "B.Cu")
		(at 208.461356 -388.692136)
		(property "Reference" "PR2519"
			(at 0 0 0)
			(layer "B.SilkS")
			(hide yes)
			(effects
				(font
					(size 1.27 1.27)
				)
				(justify mirror)
			)
		)
		(property "Value" ""
			(at 0 0 0)
			(layer "B.Fab")
			(effects
				(font
					(size 1.27 1.27)
				)
				(justify mirror)
			)
		)
		(duplicate_pad_numbers_are_jumpers no)
		(fp_line
			(start -0.7874 -0.4064)
			(end -0.7874 0.4064)
			(stroke
				(width 0.1524)
				(type default)
			)
			(layer "B.SilkS")
		)
		(fp_line
			(start -0.7874 0.4064)
			(end 0.7874 0.4064)
			(stroke
				(width 0.1524)
				(type default)
			)
			(layer "B.SilkS")
		)
		(fp_line
			(start 0.7874 -0.4064)
			(end -0.7874 -0.4064)
			(stroke
				(width 0.1524)
				(type default)
			)
			(layer "B.SilkS")
		)
		(fp_line
			(start 0.7874 0.4064)
			(end 0.7874 -0.4064)
			(stroke
				(width 0.1524)
				(type default)
			)
			(layer "B.SilkS")
		)
		(fp_line
			(start -0.67945 -0.3048)
			(end -0.67945 0.3048)
			(stroke
				(width 0.1)
				(type default)
			)
			(layer "B.Fab")
		)
		(fp_line
			(start -0.67945 0.3048)
			(end -0.120396 0.3048)
			(stroke
				(width 0.1)
				(type default)
			)
			(layer "B.Fab")
		)
		(fp_line
			(start -0.12065 -0.3048)
			(end -0.67945 -0.3048)
			(stroke
				(width 0.1)
				(type default)
			)
			(layer "B.Fab")
		)
		(fp_line
			(start -0.12065 -0.2794)
			(end -0.12065 -0.3048)
			(stroke
				(width 0.1)
				(type default)
			)
			(layer "B.Fab")
		)
		(fp_line
			(start -0.120396 0.2794)
			(end 0.12065 0.2794)
			(stroke
				(width 0.1)
				(type default)
			)
			(layer "B.Fab")
		)
		(fp_line
			(start -0.120396 0.3048)
			(end -0.120396 0.2794)
			(stroke
				(width 0.1)
				(type default)
			)
			(layer "B.Fab")
		)
		(fp_line
			(start 0.12065 -0.305054)
			(end 0.12065 -0.2794)
			(stroke
				(width 0.1)
				(type default)
			)
			(layer "B.Fab")
		)
		(fp_line
			(start 0.12065 -0.2794)
			(end -0.12065 -0.2794)
			(stroke
				(width 0.1)
				(type default)
			)
			(layer "B.Fab")
		)
		(fp_line
			(start 0.12065 0.2794)
			(end 0.12065 0.3048)
			(stroke
				(width 0.1)
				(type default)
			)
			(layer "B.Fab")
		)
		(fp_line
			(start 0.12065 0.3048)
			(end 0.67945 0.3048)
			(stroke
				(width 0.1)
				(type default)
			)
			(layer "B.Fab")
		)
		(fp_line
			(start 0.67945 -0.305054)
			(end 0.12065 -0.305054)
			(stroke
				(width 0.1)
				(type default)
			)
			(layer "B.Fab")
		)
		(fp_line
			(start 0.67945 0.3048)
			(end 0.67945 -0.305054)
			(stroke
				(width 0.1)
				(type default)
			)
			(layer "B.Fab")
		)
		(pad "1" smd circle
			(at 0.40005 0 180)
			(size 0 0)
			(layers "B.Cu" "B.Mask" "B.Paste")
			(net "P12V_HSC_ADC_N")
		)
		(pad "2" smd circle
			(at -0.40005 0 180)
			(size 0 0)
			(layers "B.Cu" "B.Mask" "B.Paste")
			(net "P12V_HSC_SENSE1_N")
		)
	)
	(footprint ""
		(layer "B.Cu")
		(at 413.123634 -193.99631)
		(property "Reference" "R96"
			(at 0 0 0)
			(layer "B.SilkS")
			(hide yes)
			(effects
				(font
					(size 1.27 1.27)
				)
				(justify mirror)
			)
		)
		(property "Value" ""
			(at 0 0 0)
			(layer "B.Fab")
			(effects
				(font
					(size 1.27 1.27)
				)
				(justify mirror)
			)
		)
		(duplicate_pad_numbers_are_jumpers no)
		(fp_line
			(start -0.7874 -0.4064)
			(end -0.7874 0.4064)
			(stroke
				(width 0.1524)
				(type default)
			)
			(layer "B.SilkS")
		)
		(fp_line
			(start -0.7874 0.4064)
			(end 0.7874 0.4064)
			(stroke
				(width 0.1524)
				(type default)
			)
			(layer "B.SilkS")
		)
		(fp_line
			(start 0.7874 -0.4064)
			(end -0.7874 -0.4064)
			(stroke
				(width 0.1524)
				(type default)
			)
			(layer "B.SilkS")
		)
		(fp_line
			(start 0.7874 0.4064)
			(end 0.7874 -0.4064)
			(stroke
				(width 0.1524)
				(type default)
			)
			(layer "B.SilkS")
		)
		(fp_line
			(start -0.67945 -0.3048)
			(end -0.67945 0.3048)
			(stroke
				(width 0.1)
				(type default)
			)
			(layer "B.Fab")
		)
		(fp_line
			(start -0.67945 0.3048)
			(end -0.120396 0.3048)
			(stroke
				(width 0.1)
				(type default)
			)
			(layer "B.Fab")
		)
		(fp_line
			(start -0.12065 -0.3048)
			(end -0.67945 -0.3048)
			(stroke
				(width 0.1)
				(type default)
			)
			(layer "B.Fab")
		)
		(fp_line
			(start -0.12065 -0.2794)
			(end -0.12065 -0.3048)
			(stroke
				(width 0.1)
				(type default)
			)
			(layer "B.Fab")
		)
		(fp_line
			(start -0.120396 0.2794)
			(end 0.12065 0.2794)
			(stroke
				(width 0.1)
				(type default)
			)
			(layer "B.Fab")
		)
		(fp_line
			(start -0.120396 0.3048)
			(end -0.120396 0.2794)
			(stroke
				(width 0.1)
				(type default)
			)
			(layer "B.Fab")
		)
		(fp_line
			(start 0.12065 -0.305054)
			(end 0.12065 -0.2794)
			(stroke
				(width 0.1)
				(type default)
			)
			(layer "B.Fab")
		)
		(fp_line
			(start 0.12065 -0.2794)
			(end -0.12065 -0.2794)
			(stroke
				(width 0.1)
				(type default)
			)
			(layer "B.Fab")
		)
		(fp_line
			(start 0.12065 0.2794)
			(end 0.12065 0.3048)
			(stroke
				(width 0.1)
				(type default)
			)
			(layer "B.Fab")
		)
		(fp_line
			(start 0.12065 0.3048)
			(end 0.67945 0.3048)
			(stroke
				(width 0.1)
				(type default)
			)
			(layer "B.Fab")
		)
		(fp_line
			(start 0.67945 -0.305054)
			(end 0.12065 -0.305054)
			(stroke
				(width 0.1)
				(type default)
			)
			(layer "B.Fab")
		)
		(fp_line
			(start 0.67945 0.3048)
			(end 0.67945 -0.305054)
			(stroke
				(width 0.1)
				(type default)
			)
			(layer "B.Fab")
		)
		(pad "1" smd circle
			(at 0.40005 0 180)
			(size 0 0)
			(layers "B.Cu" "B.Mask" "B.Paste")
			(net "P3V3")
		)
		(pad "2" smd circle
			(at -0.40005 0 180)
			(size 0 0)
			(layers "B.Cu" "B.Mask" "B.Paste")
			(net "PWRGD_CHG_CPU0_DIMM0")
		)
	)
)
